# S9S_MB_2U (Grand Teton) — schematic netlist excerpt (pin names and nets, part order shuffled) for the footprints in the layout excerpt that follows; sources: Cadence DE-HDL packaged netlist, KiCad conversion of 03242023_DA0F0TMBIJ0_F0T_Motherboard_J_brd_V01_OCP.brd

R612  Q_RES  10K 1% EMPTY  pkg 0402LF  page 199 : A = FM_PCH_EXTERNALCLKMODE ; B = GND
C1529  Q_CAP_DIFFBUS  DIFF BUS_0.22UF 6.3V 20% X6S  pkg C0201  page 177 : \1\ = P5E_CPU1_PE3_TX_C_DP<9> ; \2\ = P5E_CPU1_PE3_TX_DP<9>
R3560  Q_RES  0 5% CHIP  pkg 0402LF  page 172 : A = M2_0_P3V3_ADC_ALERT_R ; B = M2_0_P3V3_ADC_ALERT

(kicad_pcb
	(version 20260206)
	(generator "pcbnew")
	(generator_version "10.0")
	(general
		(thickness 1.6)
		(legacy_teardrops no)
	)
	(paper "A4")
	(title_block
		(title "03242023_DA0F0TMBIJ0_F0T_Motherboard_J_brd_V01_OCP.brd")
		(comment 1 "Grand Teton / footprints 1190-1192 of 6105")
	)
	(layers
		(0 "F.Cu" signal "TOP")
		(4 "In1.Cu" signal "GND")
		(6 "In2.Cu" signal "IN1")
		(8 "In3.Cu" signal "GND1")
		(10 "In4.Cu" signal "IN2")
		(12 "In5.Cu" signal "GND2")
		(14 "In6.Cu" signal "IN3")
		(16 "In7.Cu" signal "GND3")
		(18 "In8.Cu" signal "VCC")
		(20 "In9.Cu" signal "VCC1")
		(22 "In10.Cu" signal "GND4")
		(24 "In11.Cu" signal "IN4")
		(26 "In12.Cu" signal "GND5")
		(28 "In13.Cu" signal "IN5")
		(30 "In14.Cu" signal "GND6")
		(32 "In15.Cu" signal "IN6")
		(34 "In16.Cu" signal "GND7")
		(2 "B.Cu" signal "BOTTOM")
		(9 "F.Adhes" user "F.Adhesive")
		(11 "B.Adhes" user "B.Adhesive")
		(13 "F.Paste" user "Package Geometry/Pastemask Top")
		(15 "B.Paste" user "Package Geometry/Pastemask Bottom")
		(5 "F.SilkS" user "Ref Des/Silkscreen Top")
		(7 "B.SilkS" user "Ref Des/Silkscreen Bottom")
		(1 "F.Mask" user "Board Geometry/Soldermask Top")
		(3 "B.Mask" user "Board Geometry/Soldermask Bottom")
		(17 "Dwgs.User" user "User.Drawings")
		(19 "Cmts.User" user "User.Comments")
		(21 "Eco1.User" user "User.Eco1")
		(23 "Eco2.User" user "User.Eco2")
		(25 "Edge.Cuts" user "Board Geometry/Outline")
		(27 "Margin" user)
		(31 "F.CrtYd" user "Package Geometry/Place Bound Top")
		(29 "B.CrtYd" user "Package Geometry/Place Bound Bottom")
		(35 "F.Fab" user "Ref Des/Assembly Top")
		(33 "B.Fab" user "Ref Des/Assembly Bottom")
	)
	(footprint ""
		(layer "F.Cu")
		(at 148.197824 -49.372012 180)
		(property "Reference" "R3560"
			(at 0 0 180)
			(layer "F.SilkS")
			(hide yes)
			(effects
				(font
					(size 1.27 1.27)
				)
			)
		)
		(property "Value" ""
			(at 0 0 180)
			(layer "F.Fab")
			(effects
				(font
					(size 1.27 1.27)
				)
			)
		)
		(duplicate_pad_numbers_are_jumpers no)
		(fp_line
			(start 0.7874 0.4064)
			(end -0.7874 0.4064)
			(stroke
				(width 0.1524)
				(type default)
			)
			(layer "F.SilkS")
		)
		(fp_line
			(start 0.7874 -0.4064)
			(end 0.7874 0.4064)
			(stroke
				(width 0.1524)
				(type default)
			)
			(layer "F.SilkS")
		)
		(fp_line
			(start -0.7874 0.4064)
			(end -0.7874 -0.4064)
			(stroke
				(width 0.1524)
				(type default)
			)
			(layer "F.SilkS")
		)
		(fp_line
			(start -0.7874 -0.4064)
			(end 0.7874 -0.4064)
			(stroke
				(width 0.1524)
				(type default)
			)
			(layer "F.SilkS")
		)
		(fp_line
			(start 0.67945 0.3048)
			(end 0.120396 0.3048)
			(stroke
				(width 0.1)
				(type default)
			)
			(layer "F.Fab")
		)
		(fp_line
			(start 0.67945 -0.3048)
			(end 0.67945 0.3048)
			(stroke
				(width 0.1)
				(type default)
			)
			(layer "F.Fab")
		)
		(fp_line
			(start 0.12065 -0.2794)
			(end 0.12065 -0.3048)
			(stroke
				(width 0.1)
				(type default)
			)
			(layer "F.Fab")
		)
		(fp_line
			(start 0.12065 -0.3048)
			(end 0.67945 -0.3048)
			(stroke
				(width 0.1)
				(type default)
			)
			(layer "F.Fab")
		)
		(fp_line
			(start 0.120396 0.3048)
			(end 0.120396 0.2794)
			(stroke
				(width 0.1)
				(type default)
			)
			(layer "F.Fab")
		)
		(fp_line
			(start 0.120396 0.2794)
			(end -0.12065 0.2794)
			(stroke
				(width 0.1)
				(type default)
			)
			(layer "F.Fab")
		)
		(fp_line
			(start -0.12065 0.3048)
			(end -0.67945 0.3048)
			(stroke
				(width 0.1)
				(type default)
			)
			(layer "F.Fab")
		)
		(fp_line
			(start -0.12065 0.2794)
			(end -0.12065 0.3048)
			(stroke
				(width 0.1)
				(type default)
			)
			(layer "F.Fab")
		)
		(fp_line
			(start -0.12065 -0.2794)
			(end 0.12065 -0.2794)
			(stroke
				(width 0.1)
				(type default)
			)
			(layer "F.Fab")
		)
		(fp_line
			(start -0.12065 -0.305054)
			(end -0.12065 -0.2794)
			(stroke
				(width 0.1)
				(type default)
			)
			(layer "F.Fab")
		)
		(fp_line
			(start -0.67945 0.3048)
			(end -0.67945 -0.305054)
			(stroke
				(width 0.1)
				(type default)
			)
			(layer "F.Fab")
		)
		(fp_line
			(start -0.67945 -0.305054)
			(end -0.12065 -0.305054)
			(stroke
				(width 0.1)
				(type default)
			)
			(layer "F.Fab")
		)
		(pad "1" smd circle
			(at -0.40005 0 180)
			(size 0 0)
			(layers "F.Cu" "F.Mask" "F.Paste")
			(net "M2_0_P3V3_ADC_ALERT_R")
		)
		(pad "2" smd circle
			(at 0.40005 0 180)
			(size 0 0)
			(layers "F.Cu" "F.Mask" "F.Paste")
			(net "M2_0_P3V3_ADC_ALERT")
		)
	)
	(footprint ""
		(layer "F.Cu")
		(at 140.769594 -408.517344 -90)
		(property "Reference" "C1529"
			(at 0 0 270)
			(layer "F.SilkS")
			(hide yes)
			(effects
				(font
					(size 1.27 1.27)
				)
			)
		)
		(property "Value" ""
			(at 0 0 270)
			(layer "F.Fab")
			(effects
				(font
					(size 1.27 1.27)
				)
			)
		)
		(duplicate_pad_numbers_are_jumpers no)
		(fp_line
			(start -0.299974 0.150114)
			(end -0.299974 -0.150114)
			(stroke
				(width 0.1)
				(type default)
			)
			(layer "F.Fab")
		)
		(fp_line
			(start 0.299974 0.150114)
			(end -0.299974 0.150114)
			(stroke
				(width 0.1)
				(type default)
			)
			(layer "F.Fab")
		)
		(fp_line
			(start -0.299974 -0.150114)
			(end 0.299974 -0.150114)
			(stroke
				(width 0.1)
				(type default)
			)
			(layer "F.Fab")
		)
		(fp_line
			(start 0.299974 -0.150114)
			(end 0.299974 0.150114)
			(stroke
				(width 0.1)
				(type default)
			)
			(layer "F.Fab")
		)
		(pad "1" smd rect
			(at -0.2667 0 270)
			(size 0.3048 0.381)
			(layers "F.Cu" "F.Mask" "F.Paste")
			(net "P5E_CPU1_PE3_TX_C_DP<9>")
		)
		(pad "2" smd rect
			(at 0.2667 0 270)
			(size 0.3048 0.381)
			(layers "F.Cu" "F.Mask" "F.Paste")
			(net "P5E_CPU1_PE3_TX_DP<9>")
		)
	)
	(footprint ""
		(layer "F.Cu")
		(at 317.396622 -56.759348 180)
		(property "Reference" "R612"
			(at 0 0 180)
			(layer "F.SilkS")
			(hide yes)
			(effects
				(font
					(size 1.27 1.27)
				)
			)
		)
		(property "Value" ""
			(at 0 0 180)
			(layer "F.Fab")
			(effects
				(font
					(size 1.27 1.27)
				)
			)
		)
		(duplicate_pad_numbers_are_jumpers no)
		(fp_line
			(start 0.7874 0.4064)
			(end -0.7874 0.4064)
			(stroke
				(width 0.1524)
				(type default)
			)
			(layer "F.SilkS")
		)
		(fp_line
			(start 0.7874 -0.4064)
			(end 0.7874 0.4064)
			(stroke
				(width 0.1524)
				(type default)
			)
			(layer "F.SilkS")
		)
		(fp_line
			(start -0.7874 0.4064)
			(end -0.7874 -0.4064)
			(stroke
				(width 0.1524)
				(type default)
			)
			(layer "F.SilkS")
		)
		(fp_line
			(start -0.7874 -0.4064)
			(end 0.7874 -0.4064)
			(stroke
				(width 0.1524)
				(type default)
			)
			(layer "F.SilkS")
		)
		(fp_line
			(start 0.67945 0.3048)
			(end 0.120396 0.3048)
			(stroke
				(width 0.1)
				(type default)
			)
			(layer "F.Fab")
		)
		(fp_line
			(start 0.67945 -0.3048)
			(end 0.67945 0.3048)
			(stroke
				(width 0.1)
				(type default)
			)
			(layer "F.Fab")
		)
		(fp_line
			(start 0.12065 -0.2794)
			(end 0.12065 -0.3048)
			(stroke
				(width 0.1)
				(type default)
			)
			(layer "F.Fab")
		)
		(fp_line
			(start 0.12065 -0.3048)
			(end 0.67945 -0.3048)
			(stroke
				(width 0.1)
				(type default)
			)
			(layer "F.Fab")
		)
		(fp_line
			(start 0.120396 0.3048)
			(end 0.120396 0.2794)
			(stroke
				(width 0.1)
				(type default)
			)
			(layer "F.Fab")
		)
		(fp_line
			(start 0.120396 0.2794)
			(end -0.12065 0.2794)
			(stroke
				(width 0.1)
				(type default)
			)
			(layer "F.Fab")
		)
		(fp_line
			(start -0.12065 0.3048)
			(end -0.67945 0.3048)
			(stroke
				(width 0.1)
				(type default)
			)
			(layer "F.Fab")
		)
		(fp_line
			(start -0.12065 0.2794)
			(end -0.12065 0.3048)
			(stroke
				(width 0.1)
				(type default)
			)
			(layer "F.Fab")
		)
		(fp_line
			(start -0.12065 -0.2794)
			(end 0.12065 -0.2794)
			(stroke
				(width 0.1)
				(type default)
			)
			(layer "F.Fab")
		)
		(fp_line
			(start -0.12065 -0.305054)
			(end -0.12065 -0.2794)
			(stroke
				(width 0.1)
				(type default)
			)
			(layer "F.Fab")
		)
		(fp_line
			(start -0.67945 0.3048)
			(end -0.67945 -0.305054)
			(stroke
				(width 0.1)
				(type default)
			)
			(layer "F.Fab")
		)
		(fp_line
			(start -0.67945 -0.305054)
			(end -0.12065 -0.305054)
			(stroke
				(width 0.1)
				(type default)
			)
			(layer "F.Fab")
		)
		(pad "1" smd circle
			(at -0.40005 0 180)
			(size 0 0)
			(layers "F.Cu" "F.Mask" "F.Paste")
			(net "FM_PCH_EXTERNALCLKMODE")
		)
		(pad "2" smd circle
			(at 0.40005 0 180)
			(size 0 0)
			(layers "F.Cu" "F.Mask" "F.Paste")
			(net "GND")
		)
	)
)
